# BASEBOARD_FAB2 (Tioga Pass) — schematic netlist excerpt (pin names and nets, part order shuffled) for the footprints in the layout excerpt that follows; sources: Cadence DE-HDL packaged netlist, KiCad conversion of Wiwynn_Tioga_Pass_MB.brd

C9M10  CAP  10UF 16V 10% X6S  pkg 0805  page 198 : A = P12V_STBY ; B = GND
C8C4  CAP  10UF 6.3V 20% X6S  pkg 0603  page 130 : A = P3V3_STBY ; B = GND
C1M32  CAP_A  1.0UF 6.3V 10% X6S  pkg 0402V  page 113 : A = P3V3_STBY ; B = GND

(kicad_pcb
	(version 20260206)
	(generator "pcbnew")
	(generator_version "10.0")
	(general
		(thickness 1.6)
		(legacy_teardrops no)
	)
	(paper "A4")
	(title_block
		(title "Wiwynn_Tioga_Pass_MB.brd")
		(comment 1 "Tioga Pass / footprints 2842-2844 of 4770")
	)
	(layers
		(0 "F.Cu" signal "TOP")
		(4 "In1.Cu" signal "L2GND")
		(6 "In2.Cu" signal "L3")
		(8 "In3.Cu" signal "L4GND")
		(10 "In4.Cu" signal "L5")
		(12 "In5.Cu" signal "L6GND")
		(14 "In6.Cu" signal "L7VCC")
		(16 "In7.Cu" signal "L8VCC")
		(18 "In8.Cu" signal "L9GND")
		(20 "In9.Cu" signal "L10")
		(22 "In10.Cu" signal "L11GND")
		(24 "In11.Cu" signal "L12")
		(26 "In12.Cu" signal "L13GND")
		(2 "B.Cu" signal "BOTTOM")
		(9 "F.Adhes" user "F.Adhesive")
		(11 "B.Adhes" user "B.Adhesive")
		(13 "F.Paste" user "Package Geometry/Pastemask Top")
		(15 "B.Paste" user "Package Geometry/Pastemask Bottom")
		(5 "F.SilkS" user "Ref Des/Silkscreen Top")
		(7 "B.SilkS" user "Ref Des/Silkscreen Bottom")
		(1 "F.Mask" user "Board Geometry/Soldermask Top")
		(3 "B.Mask" user "Board Geometry/Soldermask Bottom")
		(17 "Dwgs.User" user "User.Drawings")
		(19 "Cmts.User" user "User.Comments")
		(21 "Eco1.User" user "User.Eco1")
		(23 "Eco2.User" user "User.Eco2")
		(25 "Edge.Cuts" user "Board Geometry/Outline")
		(27 "Margin" user)
		(31 "F.CrtYd" user "Package Geometry/Place Bound Top")
		(29 "B.CrtYd" user "Package Geometry/Place Bound Bottom")
		(35 "F.Fab" user "Ref Des/Assembly Top")
		(33 "B.Fab" user "Ref Des/Assembly Bottom")
	)
	(footprint ""
		(layer "B.Cu")
		(at -1.06426 -115.3668 -90)
		(property "Reference" "C9M10"
			(at 0 0 90)
			(layer "B.SilkS")
			(hide yes)
			(effects
				(font
					(size 1.27 1.27)
				)
				(justify mirror)
			)
		)
		(property "Value" ""
			(at 0 0 90)
			(layer "B.Fab")
			(effects
				(font
					(size 1.27 1.27)
				)
				(justify mirror)
			)
		)
		(duplicate_pad_numbers_are_jumpers no)
		(fp_poly
			(pts
				(xy 0.7239 -0.2159) (xy -0.7239 -0.2159) (xy -0.7239 1.9939) (xy 0.7239 1.9939)
			)
			(stroke
				(width 0)
				(type default)
			)
			(fill no)
			(layer "B.CrtYd")
		)
		(fp_line
			(start -0.7239 1.9939)
			(end -0.7239 -0.2159)
			(stroke
				(width 0.1)
				(type default)
			)
			(layer "B.Fab")
		)
		(fp_line
			(start 0.7239 1.9939)
			(end -0.7239 1.9939)
			(stroke
				(width 0.1)
				(type default)
			)
			(layer "B.Fab")
		)
		(fp_line
			(start -0.7239 -0.2159)
			(end 0.7239 -0.2159)
			(stroke
				(width 0.1)
				(type default)
			)
			(layer "B.Fab")
		)
		(fp_line
			(start 0.7239 -0.2159)
			(end 0.7239 1.9939)
			(stroke
				(width 0.1)
				(type default)
			)
			(layer "B.Fab")
		)
		(pad "1" smd rect
			(at 0 0 90)
			(size 1.27 1.016)
			(layers "B.Cu" "B.Mask" "B.Paste")
			(net "P12V_STBY")
		)
		(pad "2" smd rect
			(at 0 1.778 90)
			(size 1.27 1.016)
			(layers "B.Cu" "B.Mask" "B.Paste")
			(net "GND")
		)
		(zone
			(layer "B.Cu")
			(hatch none 0.5)
			(connect_pads
				(clearance 0)
			)
			(min_thickness 0.25)
			(keepout
				(tracks not_allowed)
				(vias allowed)
				(pads allowed)
				(copperpour not_allowed)
				(footprints allowed)
			)
			(placement
				(enabled no)
				(sheetname "")
			)
			(fill
				(thermal_gap 0.5)
				(thermal_bridge_width 0.5)
				(island_removal_mode 0)
			)
			(polygon
				(pts
					(xy -1.57226 -114.7318) (xy -1.57226 -116.0018) (xy -2.33426 -116.0018) (xy -2.33426 -114.7318)
				)
			)
		)
	)
	(footprint ""
		(layer "B.Cu")
		(at 406.654 -93.280992 90)
		(property "Reference" "C8C4"
			(at 0 0 90)
			(layer "B.SilkS")
			(hide yes)
			(effects
				(font
					(size 1.27 1.27)
				)
				(justify mirror)
			)
		)
		(property "Value" ""
			(at 0 0 90)
			(layer "B.Fab")
			(effects
				(font
					(size 1.27 1.27)
				)
				(justify mirror)
			)
		)
		(duplicate_pad_numbers_are_jumpers no)
		(fp_poly
			(pts
				(xy 0.4953 -0.2032) (xy -0.4953 -0.2032) (xy -0.4953 1.6002) (xy 0.4953 1.6002)
			)
			(stroke
				(width 0)
				(type default)
			)
			(fill no)
			(layer "B.CrtYd")
		)
		(fp_line
			(start 0.4953 -0.2032)
			(end -0.4953 -0.2032)
			(stroke
				(width 0.1)
				(type default)
			)
			(layer "B.Fab")
		)
		(fp_line
			(start -0.4953 -0.2032)
			(end -0.4953 1.6002)
			(stroke
				(width 0.1)
				(type default)
			)
			(layer "B.Fab")
		)
		(fp_line
			(start 0.4953 1.6002)
			(end 0.4953 -0.2032)
			(stroke
				(width 0.1)
				(type default)
			)
			(layer "B.Fab")
		)
		(fp_line
			(start -0.4953 1.6002)
			(end 0.4953 1.6002)
			(stroke
				(width 0.1)
				(type default)
			)
			(layer "B.Fab")
		)
		(pad "1" smd rect
			(at 0 0 270)
			(size 0.762 0.889)
			(layers "B.Cu" "B.Mask" "B.Paste")
			(net "P3V3_STBY")
		)
		(pad "2" smd rect
			(at 0 1.397 270)
			(size 0.762 0.889)
			(layers "B.Cu" "B.Mask" "B.Paste")
			(net "GND")
		)
		(zone
			(layer "B.Cu")
			(hatch none 0.5)
			(connect_pads
				(clearance 0)
			)
			(min_thickness 0.25)
			(keepout
				(tracks not_allowed)
				(vias allowed)
				(pads allowed)
				(copperpour not_allowed)
				(footprints allowed)
			)
			(placement
				(enabled no)
				(sheetname "")
			)
			(fill
				(thermal_gap 0.5)
				(thermal_bridge_width 0.5)
				(island_removal_mode 0)
			)
			(polygon
				(pts
					(xy 407.0985 -93.661992) (xy 407.0985 -92.899992) (xy 407.6065 -92.899992) (xy 407.6065 -93.661992)
				)
			)
		)
	)
	(footprint ""
		(layer "B.Cu")
		(at 495.45748 -130.52552)
		(property "Reference" "C1M32"
			(at 0 0 0)
			(layer "B.SilkS")
			(hide yes)
			(effects
				(font
					(size 1.27 1.27)
				)
				(justify mirror)
			)
		)
		(property "Value" ""
			(at 0 0 0)
			(layer "B.Fab")
			(effects
				(font
					(size 1.27 1.27)
				)
				(justify mirror)
			)
		)
		(duplicate_pad_numbers_are_jumpers no)
		(fp_poly
			(pts
				(xy -0.3048 -0.1016) (xy -0.3048 0.9906) (xy 0.3048 0.9906) (xy 0.3048 -0.1016)
			)
			(stroke
				(width 0)
				(type default)
			)
			(fill no)
			(layer "B.CrtYd")
		)
		(fp_line
			(start -0.3048 -0.1016)
			(end 0.3048 -0.1016)
			(stroke
				(width 0.1)
				(type default)
			)
			(layer "B.Fab")
		)
		(fp_line
			(start -0.3048 0.9906)
			(end -0.3048 -0.1016)
			(stroke
				(width 0.1)
				(type default)
			)
			(layer "B.Fab")
		)
		(fp_line
			(start 0.3048 -0.1016)
			(end 0.3048 0.9906)
			(stroke
				(width 0.1)
				(type default)
			)
			(layer "B.Fab")
		)
		(fp_line
			(start 0.3048 0.9906)
			(end -0.3048 0.9906)
			(stroke
				(width 0.1)
				(type default)
			)
			(layer "B.Fab")
		)
		(pad "1" smd rect
			(at 0 0 180)
			(size 0.508 0.508)
			(layers "B.Cu" "B.Mask" "B.Paste")
			(net "P3V3_STBY")
		)
		(pad "2" smd rect
			(at 0 0.889 180)
			(size 0.508 0.508)
			(layers "B.Cu" "B.Mask" "B.Paste")
			(net "GND")
		)
		(zone
			(layer "B.Cu")
			(hatch none 0.5)
			(connect_pads
				(clearance 0)
			)
			(min_thickness 0.25)
			(keepout
				(tracks allowed)
				(vias not_allowed)
				(pads allowed)
				(copperpour not_allowed)
				(footprints allowed)
			)
			(placement
				(enabled no)
				(sheetname "")
			)
			(fill
				(thermal_gap 0.5)
				(thermal_bridge_width 0.5)
				(island_removal_mode 0)
			)
			(polygon
				(pts
					(xy 495.71148 -130.27152) (xy 495.20348 -130.27152) (xy 495.20348 -129.89052) (xy 495.71148 -129.89052)
				)
			)
		)
		(zone
			(layer "B.Cu")
			(hatch none 0.5)
			(connect_pads
				(clearance 0)
			)
			(min_thickness 0.25)
			(keepout
				(tracks not_allowed)
				(vias allowed)
				(pads allowed)
				(copperpour not_allowed)
				(footprints allowed)
			)
			(placement
				(enabled no)
				(sheetname "")
			)
			(fill
				(thermal_gap 0.5)
				(thermal_bridge_width 0.5)
				(island_removal_mode 0)
			)
			(polygon
				(pts
					(xy 495.71148 -129.89052) (xy 495.20348 -129.89052) (xy 495.20348 -130.27152) (xy 495.71148 -130.27152)
				)
			)
		)
	)
)
